# T6G (Grand Teton) — schematic netlist excerpt (pin names and nets, part order shuffled) for the footprints in the layout excerpt that follows; sources: Cadence DE-HDL packaged netlist, KiCad conversion of 04192023_DAF0TMB3IC0_F0TG_MB_C_brd_V02_OCP.brd

C688  Q_CAP_DIFFBUS  DIFF BUS_0.22UF 6.3V 20% X6S  pkg C0201  page 67 : \1\ = P5E_CPU1_G1_TX_C_DN<10> ; \2\ = P5E_CPU1_G1_TX_DN<10>
R1729  Q_RES  4.7K 5% CHIP  pkg 0402LF  page 171 : A = SCM_JTAG_MUX_S1 ; B = GND

(kicad_pcb
	(version 20260206)
	(generator "pcbnew")
	(generator_version "10.0")
	(general
		(thickness 1.6)
		(legacy_teardrops no)
	)
	(paper "A4")
	(title_block
		(title "04192023_DAF0TMB3IC0_F0TG_MB_C_brd_V02_OCP.brd")
		(comment 1 "Grand Teton / footprints 228-229 of 8354")
	)
	(layers
		(0 "F.Cu" signal "TOP")
		(4 "In1.Cu" signal "GND")
		(6 "In2.Cu" signal "IN1")
		(8 "In3.Cu" signal "GND1")
		(10 "In4.Cu" signal "IN2")
		(12 "In5.Cu" signal "GND2")
		(14 "In6.Cu" signal "IN3")
		(16 "In7.Cu" signal "GND3")
		(18 "In8.Cu" signal "VCC")
		(20 "In9.Cu" signal "VCC1")
		(22 "In10.Cu" signal "GND4")
		(24 "In11.Cu" signal "IN4")
		(26 "In12.Cu" signal "GND5")
		(28 "In13.Cu" signal "IN5")
		(30 "In14.Cu" signal "GND6")
		(32 "In15.Cu" signal "IN6")
		(34 "In16.Cu" signal "GND7")
		(2 "B.Cu" signal "BOTTOM")
		(9 "F.Adhes" user "F.Adhesive")
		(11 "B.Adhes" user "B.Adhesive")
		(13 "F.Paste" user "Package Geometry/Pastemask Top")
		(15 "B.Paste" user "Package Geometry/Pastemask Bottom")
		(5 "F.SilkS" user "Ref Des/Silkscreen Top")
		(7 "B.SilkS" user "Ref Des/Silkscreen Bottom")
		(1 "F.Mask" user "Board Geometry/Soldermask Top")
		(3 "B.Mask" user "Board Geometry/Soldermask Bottom")
		(17 "Dwgs.User" user "User.Drawings")
		(19 "Cmts.User" user "User.Comments")
		(21 "Eco1.User" user "User.Eco1")
		(23 "Eco2.User" user "User.Eco2")
		(25 "Edge.Cuts" user "Board Geometry/Outline")
		(27 "Margin" user)
		(31 "F.CrtYd" user "Package Geometry/Place Bound Top")
		(29 "B.CrtYd" user "Package Geometry/Place Bound Bottom")
		(35 "F.Fab" user "Ref Des/Assembly Top")
		(33 "B.Fab" user "Ref Des/Assembly Bottom")
	)
	(footprint ""
		(layer "F.Cu")
		(at 116.314474 -55.036212 -90)
		(property "Reference" "R1729"
			(at 0 0 270)
			(layer "F.SilkS")
			(hide yes)
			(effects
				(font
					(size 1.27 1.27)
				)
			)
		)
		(property "Value" ""
			(at 0 0 270)
			(layer "F.Fab")
			(effects
				(font
					(size 1.27 1.27)
				)
			)
		)
		(duplicate_pad_numbers_are_jumpers no)
		(fp_line
			(start -0.7874 0.4064)
			(end -0.7874 -0.4064)
			(stroke
				(width 0.1524)
				(type default)
			)
			(layer "F.SilkS")
		)
		(fp_line
			(start 0.7874 0.4064)
			(end -0.7874 0.4064)
			(stroke
				(width 0.1524)
				(type default)
			)
			(layer "F.SilkS")
		)
		(fp_line
			(start -0.7874 -0.4064)
			(end 0.7874 -0.4064)
			(stroke
				(width 0.1524)
				(type default)
			)
			(layer "F.SilkS")
		)
		(fp_line
			(start 0.7874 -0.4064)
			(end 0.7874 0.4064)
			(stroke
				(width 0.1524)
				(type default)
			)
			(layer "F.SilkS")
		)
		(fp_line
			(start -0.67945 0.3048)
			(end -0.67945 -0.305054)
			(stroke
				(width 0.1)
				(type default)
			)
			(layer "F.Fab")
		)
		(fp_line
			(start -0.12065 0.3048)
			(end -0.67945 0.3048)
			(stroke
				(width 0.1)
				(type default)
			)
			(layer "F.Fab")
		)
		(fp_line
			(start 0.120396 0.3048)
			(end 0.120396 0.2794)
			(stroke
				(width 0.1)
				(type default)
			)
			(layer "F.Fab")
		)
		(fp_line
			(start 0.67945 0.3048)
			(end 0.120396 0.3048)
			(stroke
				(width 0.1)
				(type default)
			)
			(layer "F.Fab")
		)
		(fp_line
			(start -0.12065 0.2794)
			(end -0.12065 0.3048)
			(stroke
				(width 0.1)
				(type default)
			)
			(layer "F.Fab")
		)
		(fp_line
			(start 0.120396 0.2794)
			(end -0.12065 0.2794)
			(stroke
				(width 0.1)
				(type default)
			)
			(layer "F.Fab")
		)
		(fp_line
			(start -0.12065 -0.2794)
			(end 0.12065 -0.2794)
			(stroke
				(width 0.1)
				(type default)
			)
			(layer "F.Fab")
		)
		(fp_line
			(start 0.12065 -0.2794)
			(end 0.12065 -0.3048)
			(stroke
				(width 0.1)
				(type default)
			)
			(layer "F.Fab")
		)
		(fp_line
			(start 0.12065 -0.3048)
			(end 0.67945 -0.3048)
			(stroke
				(width 0.1)
				(type default)
			)
			(layer "F.Fab")
		)
		(fp_line
			(start 0.67945 -0.3048)
			(end 0.67945 0.3048)
			(stroke
				(width 0.1)
				(type default)
			)
			(layer "F.Fab")
		)
		(fp_line
			(start -0.67945 -0.305054)
			(end -0.12065 -0.305054)
			(stroke
				(width 0.1)
				(type default)
			)
			(layer "F.Fab")
		)
		(fp_line
			(start -0.12065 -0.305054)
			(end -0.12065 -0.2794)
			(stroke
				(width 0.1)
				(type default)
			)
			(layer "F.Fab")
		)
		(pad "1" smd circle
			(at -0.40005 0 270)
			(size 0 0)
			(layers "F.Cu" "F.Mask" "F.Paste")
			(net "SCM_JTAG_MUX_S1")
		)
		(pad "2" smd circle
			(at 0.40005 0 270)
			(size 0 0)
			(layers "F.Cu" "F.Mask" "F.Paste")
			(net "GND")
		)
	)
	(footprint ""
		(layer "F.Cu")
		(at 29.478478 -17.623536 90)
		(property "Reference" "C688"
			(at 0 0 90)
			(layer "F.SilkS")
			(hide yes)
			(effects
				(font
					(size 1.27 1.27)
				)
			)
		)
		(property "Value" ""
			(at 0 0 90)
			(layer "F.Fab")
			(effects
				(font
					(size 1.27 1.27)
				)
			)
		)
		(duplicate_pad_numbers_are_jumpers no)
		(fp_line
			(start 0.299974 -0.150114)
			(end 0.299974 0.150114)
			(stroke
				(width 0.1)
				(type default)
			)
			(layer "F.Fab")
		)
		(fp_line
			(start -0.299974 -0.150114)
			(end 0.299974 -0.150114)
			(stroke
				(width 0.1)
				(type default)
			)
			(layer "F.Fab")
		)
		(fp_line
			(start 0.299974 0.150114)
			(end -0.299974 0.150114)
			(stroke
				(width 0.1)
				(type default)
			)
			(layer "F.Fab")
		)
		(fp_line
			(start -0.299974 0.150114)
			(end -0.299974 -0.150114)
			(stroke
				(width 0.1)
				(type default)
			)
			(layer "F.Fab")
		)
		(pad "1" smd rect
			(at -0.2667 0 90)
			(size 0.3048 0.381)
			(layers "F.Cu" "F.Mask" "F.Paste")
			(net "P5E_CPU1_G1_TX_C_DN<10>")
		)
		(pad "2" smd rect
			(at 0.2667 0 90)
			(size 0.3048 0.381)
			(layers "F.Cu" "F.Mask" "F.Paste")
			(net "P5E_CPU1_G1_TX_DN<10>")
		)
	)
)
